# T6G (Grand Teton) — schematic netlist excerpt (pin names and nets, part order shuffled) for the footprints in the layout excerpt that follows; sources: Cadence DE-HDL packaged netlist, KiCad conversion of 04192023_DAF0TMB3IC0_F0TG_MB_C_brd_V02_OCP.brd

Q83  MOSFET_NCH_DUAL  PJT138K IC  pkg SOT363XD  page 255
  S1  = GND
  G1  = FM_LED_PWRGD_PVDD18_S5_P0
  D2  = NC_Q83_D2
  S2  = NC_Q83_S2
  G2  = NC_Q83_G2
  D1  = LED_PWRGD_PVDD18_S5_P0_D

C2281  Q_CAP  22UF 4V 20% X6S  pkg C0402  page 72 : A = PVDDCR_SOC_P1 ; B = GND

(kicad_pcb
	(version 20260206)
	(generator "pcbnew")
	(generator_version "10.0")
	(general
		(thickness 1.6)
		(legacy_teardrops no)
	)
	(paper "A4")
	(title_block
		(title "04192023_DAF0TMB3IC0_F0TG_MB_C_brd_V02_OCP.brd")
		(comment 1 "Grand Teton / footprints 5760-5761 of 8354")
	)
	(layers
		(0 "F.Cu" signal "TOP")
		(4 "In1.Cu" signal "GND")
		(6 "In2.Cu" signal "IN1")
		(8 "In3.Cu" signal "GND1")
		(10 "In4.Cu" signal "IN2")
		(12 "In5.Cu" signal "GND2")
		(14 "In6.Cu" signal "IN3")
		(16 "In7.Cu" signal "GND3")
		(18 "In8.Cu" signal "VCC")
		(20 "In9.Cu" signal "VCC1")
		(22 "In10.Cu" signal "GND4")
		(24 "In11.Cu" signal "IN4")
		(26 "In12.Cu" signal "GND5")
		(28 "In13.Cu" signal "IN5")
		(30 "In14.Cu" signal "GND6")
		(32 "In15.Cu" signal "IN6")
		(34 "In16.Cu" signal "GND7")
		(2 "B.Cu" signal "BOTTOM")
		(9 "F.Adhes" user "F.Adhesive")
		(11 "B.Adhes" user "B.Adhesive")
		(13 "F.Paste" user "Package Geometry/Pastemask Top")
		(15 "B.Paste" user "Package Geometry/Pastemask Bottom")
		(5 "F.SilkS" user "Ref Des/Silkscreen Top")
		(7 "B.SilkS" user "Ref Des/Silkscreen Bottom")
		(1 "F.Mask" user "Board Geometry/Soldermask Top")
		(3 "B.Mask" user "Board Geometry/Soldermask Bottom")
		(17 "Dwgs.User" user "User.Drawings")
		(19 "Cmts.User" user "User.Comments")
		(21 "Eco1.User" user "User.Eco1")
		(23 "Eco2.User" user "User.Eco2")
		(25 "Edge.Cuts" user "Board Geometry/Outline")
		(27 "Margin" user)
		(31 "F.CrtYd" user "Package Geometry/Place Bound Top")
		(29 "B.CrtYd" user "Package Geometry/Place Bound Bottom")
		(35 "F.Fab" user "Ref Des/Assembly Top")
		(33 "B.Fab" user "Ref Des/Assembly Bottom")
	)
	(footprint ""
		(layer "B.Cu")
		(at 113.705386 -251.781564)
		(property "Reference" "C2281"
			(at 0 0 0)
			(layer "B.SilkS")
			(hide yes)
			(effects
				(font
					(size 1.27 1.27)
				)
				(justify mirror)
			)
		)
		(property "Value" ""
			(at 0 0 0)
			(layer "B.Fab")
			(effects
				(font
					(size 1.27 1.27)
				)
				(justify mirror)
			)
		)
		(duplicate_pad_numbers_are_jumpers no)
		(fp_line
			(start -0.7874 -0.4064)
			(end -0.7874 0.4064)
			(stroke
				(width 0.1524)
				(type default)
			)
			(layer "B.SilkS")
		)
		(fp_line
			(start -0.7874 0.4064)
			(end 0.7874 0.4064)
			(stroke
				(width 0.1524)
				(type default)
			)
			(layer "B.SilkS")
		)
		(fp_line
			(start 0.7874 -0.4064)
			(end -0.7874 -0.4064)
			(stroke
				(width 0.1524)
				(type default)
			)
			(layer "B.SilkS")
		)
		(fp_line
			(start 0.7874 0.4064)
			(end 0.7874 -0.4064)
			(stroke
				(width 0.1524)
				(type default)
			)
			(layer "B.SilkS")
		)
		(fp_line
			(start -0.67945 -0.3048)
			(end -0.67945 0.3048)
			(stroke
				(width 0.1)
				(type default)
			)
			(layer "B.Fab")
		)
		(fp_line
			(start -0.67945 0.3048)
			(end -0.120396 0.3048)
			(stroke
				(width 0.1)
				(type default)
			)
			(layer "B.Fab")
		)
		(fp_line
			(start -0.12065 -0.3048)
			(end -0.67945 -0.3048)
			(stroke
				(width 0.1)
				(type default)
			)
			(layer "B.Fab")
		)
		(fp_line
			(start -0.12065 -0.2794)
			(end -0.12065 -0.3048)
			(stroke
				(width 0.1)
				(type default)
			)
			(layer "B.Fab")
		)
		(fp_line
			(start -0.120396 0.2794)
			(end 0.12065 0.2794)
			(stroke
				(width 0.1)
				(type default)
			)
			(layer "B.Fab")
		)
		(fp_line
			(start -0.120396 0.3048)
			(end -0.120396 0.2794)
			(stroke
				(width 0.1)
				(type default)
			)
			(layer "B.Fab")
		)
		(fp_line
			(start 0.12065 -0.305054)
			(end 0.12065 -0.2794)
			(stroke
				(width 0.1)
				(type default)
			)
			(layer "B.Fab")
		)
		(fp_line
			(start 0.12065 -0.2794)
			(end -0.12065 -0.2794)
			(stroke
				(width 0.1)
				(type default)
			)
			(layer "B.Fab")
		)
		(fp_line
			(start 0.12065 0.2794)
			(end 0.12065 0.3048)
			(stroke
				(width 0.1)
				(type default)
			)
			(layer "B.Fab")
		)
		(fp_line
			(start 0.12065 0.3048)
			(end 0.67945 0.3048)
			(stroke
				(width 0.1)
				(type default)
			)
			(layer "B.Fab")
		)
		(fp_line
			(start 0.67945 -0.305054)
			(end 0.12065 -0.305054)
			(stroke
				(width 0.1)
				(type default)
			)
			(layer "B.Fab")
		)
		(fp_line
			(start 0.67945 0.3048)
			(end 0.67945 -0.305054)
			(stroke
				(width 0.1)
				(type default)
			)
			(layer "B.Fab")
		)
		(pad "1" smd circle
			(at 0.40005 0 180)
			(size 0 0)
			(layers "B.Cu" "B.Mask" "B.Paste")
			(net "PVDDCR_SOC_P1")
		)
		(pad "2" smd circle
			(at -0.40005 0 180)
			(size 0 0)
			(layers "B.Cu" "B.Mask" "B.Paste")
			(net "GND")
		)
	)
	(footprint ""
		(layer "B.Cu")
		(at 332.316836 -76.35875 180)
		(property "Reference" "Q83"
			(at -2.243328 2.223008 0)
			(unlocked yes)
			(layer "B.SilkS")
			(effects
				(font
					(size 0.7874 0.5842)
					(thickness 0.1524)
				)
				(justify left mirror)
			)
		)
		(property "Value" ""
			(at 0 0 0)
			(layer "B.Fab")
			(effects
				(font
					(size 1.27 1.27)
				)
				(justify mirror)
			)
		)
		(duplicate_pad_numbers_are_jumpers no)
		(fp_line
			(start 1.332738 1.100074)
			(end 1.332738 -1.100074)
			(stroke
				(width 0.1524)
				(type default)
			)
			(layer "B.SilkS")
		)
		(fp_line
			(start 1.332738 -1.100074)
			(end 0.4826 -1.100074)
			(stroke
				(width 0.1524)
				(type default)
			)
			(layer "B.SilkS")
		)
		(fp_line
			(start 0.4826 -1.100074)
			(end 0 -0.541274)
			(stroke
				(width 0.1524)
				(type default)
			)
			(layer "B.SilkS")
		)
		(fp_line
			(start 0 -0.541274)
			(end -0.4826 -1.100074)
			(stroke
				(width 0.1524)
				(type default)
			)
			(layer "B.SilkS")
		)
		(fp_line
			(start -0.4826 -1.100074)
			(end -1.332738 -1.100074)
			(stroke
				(width 0.1524)
				(type default)
			)
			(layer "B.SilkS")
		)
		(fp_line
			(start -1.332738 1.100074)
			(end 1.332738 1.100074)
			(stroke
				(width 0.1524)
				(type default)
			)
			(layer "B.SilkS")
		)
		(fp_line
			(start -1.332738 -1.100074)
			(end -1.332738 1.100074)
			(stroke
				(width 0.1524)
				(type default)
			)
			(layer "B.SilkS")
		)
		(fp_poly
			(pts
				(xy 1.864106 -0.627888) (xy 2.566162 -0.978916) (xy 2.566162 -0.27686)
			)
			(stroke
				(width 0)
				(type default)
			)
			(fill yes)
			(layer "B.SilkS")
		)
		(fp_line
			(start 0.674878 1.100074)
			(end 0.674878 -1.100074)
			(stroke
				(width 0.1)
				(type default)
			)
			(layer "B.Fab")
		)
		(fp_line
			(start 0.674878 -1.100074)
			(end -0.674878 -1.100074)
			(stroke
				(width 0.1)
				(type default)
			)
			(layer "B.Fab")
		)
		(fp_line
			(start -0.674878 1.100074)
			(end 0.674878 1.100074)
			(stroke
				(width 0.1)
				(type default)
			)
			(layer "B.Fab")
		)
		(fp_line
			(start -0.674878 -1.100074)
			(end -0.674878 1.100074)
			(stroke
				(width 0.1)
				(type default)
			)
			(layer "B.Fab")
		)
		(fp_poly
			(pts
				(xy 2.2352 -0.298958) (xy 2.2352 -1.001014) (xy 1.533144 -0.649986)
			)
			(stroke
				(width 0)
				(type default)
			)
			(fill yes)
			(layer "B.Fab")
		)
		(pad "1" smd rect
			(at 0.94996 -0.649986 270)
			(size 0.4318 0.508)
			(layers "B.Cu" "B.Mask" "B.Paste")
			(net "GND")
		)
		(pad "2" smd rect
			(at 0.94996 0 270)
			(size 0.4318 0.508)
			(layers "B.Cu" "B.Mask" "B.Paste")
			(net "FM_LED_PWRGD_PVDD18_S5_P0")
		)
		(pad "3" smd rect
			(at 0.94996 0.649986 270)
			(size 0.4318 0.508)
			(layers "B.Cu" "B.Mask" "B.Paste")
			(net "NC_Q83_D2")
		)
		(pad "4" smd rect
			(at -0.94996 0.649986 270)
			(size 0.4318 0.508)
			(layers "B.Cu" "B.Mask" "B.Paste")
			(net "NC_Q83_S2")
		)
		(pad "5" smd rect
			(at -0.94996 0 270)
			(size 0.4318 0.508)
			(layers "B.Cu" "B.Mask" "B.Paste")
			(net "NC_Q83_G2")
		)
		(pad "6" smd rect
			(at -0.94996 -0.649986 270)
			(size 0.4318 0.508)
			(layers "B.Cu" "B.Mask" "B.Paste")
			(net "LED_PWRGD_PVDD18_S5_P0_D")
		)
	)
)
